(kicad_pcb
	(version 20260206)
	(generator "pcbnew")
	(generator_version "10.0")
	(general
		(thickness 1.6)
		(legacy_teardrops no)
	)
	(paper "A4")
	(title_block
		(title "9052_F0T_PDB_Converter_Brick_F_V03_1208_1600_OCP.brd")
		(comment 1 "Grand Teton / footprints 308-313 of 578")
	)
	(layers
		(0 "F.Cu" signal "TOP")
		(4 "In1.Cu" signal "GND")
		(6 "In2.Cu" signal "IN1")
		(8 "In3.Cu" signal "GND1")
		(10 "In4.Cu" signal "VCC")
		(12 "In5.Cu" signal "VCC1")
		(14 "In6.Cu" signal "GND2")
		(16 "In7.Cu" signal "IN2")
		(18 "In8.Cu" signal "GND3")
		(2 "B.Cu" signal "BOTTOM")
		(9 "F.Adhes" user "F.Adhesive")
		(11 "B.Adhes" user "B.Adhesive")
		(13 "F.Paste" user "Package Geometry/Pastemask Top")
		(15 "B.Paste" user "Package Geometry/Pastemask Bottom")
		(5 "F.SilkS" user "Ref Des/Silkscreen Top")
		(7 "B.SilkS" user "Ref Des/Silkscreen Bottom")
		(1 "F.Mask" user "Board Geometry/Soldermask Top")
		(3 "B.Mask" user "Board Geometry/Soldermask Bottom")
		(17 "Dwgs.User" user "User.Drawings")
		(19 "Cmts.User" user "User.Comments")
		(21 "Eco1.User" user "User.Eco1")
		(23 "Eco2.User" user "User.Eco2")
		(25 "Edge.Cuts" user "Board Geometry/Outline")
		(27 "Margin" user)
		(31 "F.CrtYd" user "Package Geometry/Place Bound Top")
		(29 "B.CrtYd" user "Package Geometry/Place Bound Bottom")
		(35 "F.Fab" user "Ref Des/Assembly Top")
		(33 "B.Fab" user "Ref Des/Assembly Bottom")
	)
	(footprint ""
		(layer "B.Cu")
		(at 210.185 -82.55 -90)
		(property "Reference" "R23"
			(at 0 0 90)
			(layer "B.SilkS")
			(hide yes)
			(effects
				(font
					(size 1.27 1.27)
				)
				(justify mirror)
			)
		)
		(property "Value" ""
			(at 0 0 90)
			(layer "B.Fab")
			(effects
				(font
					(size 1.27 1.27)
				)
				(justify mirror)
			)
		)
		(duplicate_pad_numbers_are_jumpers no)
		(fp_line
			(start -0.7874 0.4064)
			(end 0.7874 0.4064)
			(stroke
				(width 0.1524)
				(type default)
			)
			(layer "B.SilkS")
		)
		(fp_line
			(start 0.7874 0.4064)
			(end 0.7874 -0.4064)
			(stroke
				(width 0.1524)
				(type default)
			)
			(layer "B.SilkS")
		)
		(fp_line
			(start -0.7874 -0.4064)
			(end -0.7874 0.4064)
			(stroke
				(width 0.1524)
				(type default)
			)
			(layer "B.SilkS")
		)
		(fp_line
			(start 0.7874 -0.4064)
			(end -0.7874 -0.4064)
			(stroke
				(width 0.1524)
				(type default)
			)
			(layer "B.SilkS")
		)
		(fp_line
			(start -0.67945 0.3048)
			(end -0.120396 0.3048)
			(stroke
				(width 0.1)
				(type default)
			)
			(layer "B.Fab")
		)
		(fp_line
			(start -0.120396 0.3048)
			(end -0.120396 0.2794)
			(stroke
				(width 0.1)
				(type default)
			)
			(layer "B.Fab")
		)
		(fp_line
			(start 0.12065 0.3048)
			(end 0.67945 0.3048)
			(stroke
				(width 0.1)
				(type default)
			)
			(layer "B.Fab")
		)
		(fp_line
			(start 0.67945 0.3048)
			(end 0.67945 -0.305054)
			(stroke
				(width 0.1)
				(type default)
			)
			(layer "B.Fab")
		)
		(fp_line
			(start -0.120396 0.2794)
			(end 0.12065 0.2794)
			(stroke
				(width 0.1)
				(type default)
			)
			(layer "B.Fab")
		)
		(fp_line
			(start 0.12065 0.2794)
			(end 0.12065 0.3048)
			(stroke
				(width 0.1)
				(type default)
			)
			(layer "B.Fab")
		)
		(fp_line
			(start -0.12065 -0.2794)
			(end -0.12065 -0.3048)
			(stroke
				(width 0.1)
				(type default)
			)
			(layer "B.Fab")
		)
		(fp_line
			(start 0.12065 -0.2794)
			(end -0.12065 -0.2794)
			(stroke
				(width 0.1)
				(type default)
			)
			(layer "B.Fab")
		)
		(fp_line
			(start -0.67945 -0.3048)
			(end -0.67945 0.3048)
			(stroke
				(width 0.1)
				(type default)
			)
			(layer "B.Fab")
		)
		(fp_line
			(start -0.12065 -0.3048)
			(end -0.67945 -0.3048)
			(stroke
				(width 0.1)
				(type default)
			)
			(layer "B.Fab")
		)
		(fp_line
			(start 0.12065 -0.305054)
			(end 0.12065 -0.2794)
			(stroke
				(width 0.1)
				(type default)
			)
			(layer "B.Fab")
		)
		(fp_line
			(start 0.67945 -0.305054)
			(end 0.12065 -0.305054)
			(stroke
				(width 0.1)
				(type default)
			)
			(layer "B.Fab")
		)
		(pad "1" smd circle
			(at 0.40005 0 90)
			(size 0 0)
			(layers "B.Cu" "B.Mask" "B.Paste")
			(net "PCA9555_A2")
		)
		(pad "2" smd circle
			(at -0.40005 0 90)
			(size 0 0)
			(layers "B.Cu" "B.Mask" "B.Paste")
			(net "GND")
		)
	)
	(footprint ""
		(layer "B.Cu")
		(at 38.989 -85.217)
		(property "Reference" "R78"
			(at 0 0 0)
			(layer "B.SilkS")
			(hide yes)
			(effects
				(font
					(size 1.27 1.27)
				)
				(justify mirror)
			)
		)
		(property "Value" ""
			(at 0 0 0)
			(layer "B.Fab")
			(effects
				(font
					(size 1.27 1.27)
				)
				(justify mirror)
			)
		)
		(duplicate_pad_numbers_are_jumpers no)
		(fp_line
			(start -0.7874 -0.4064)
			(end -0.7874 0.4064)
			(stroke
				(width 0.1524)
				(type default)
			)
			(layer "B.SilkS")
		)
		(fp_line
			(start -0.7874 0.4064)
			(end 0.7874 0.4064)
			(stroke
				(width 0.1524)
				(type default)
			)
			(layer "B.SilkS")
		)
		(fp_line
			(start 0.7874 -0.4064)
			(end -0.7874 -0.4064)
			(stroke
				(width 0.1524)
				(type default)
			)
			(layer "B.SilkS")
		)
		(fp_line
			(start 0.7874 0.4064)
			(end 0.7874 -0.4064)
			(stroke
				(width 0.1524)
				(type default)
			)
			(layer "B.SilkS")
		)
		(fp_line
			(start -0.67945 -0.3048)
			(end -0.67945 0.3048)
			(stroke
				(width 0.1)
				(type default)
			)
			(layer "B.Fab")
		)
		(fp_line
			(start -0.67945 0.3048)
			(end -0.120396 0.3048)
			(stroke
				(width 0.1)
				(type default)
			)
			(layer "B.Fab")
		)
		(fp_line
			(start -0.12065 -0.3048)
			(end -0.67945 -0.3048)
			(stroke
				(width 0.1)
				(type default)
			)
			(layer "B.Fab")
		)
		(fp_line
			(start -0.12065 -0.2794)
			(end -0.12065 -0.3048)
			(stroke
				(width 0.1)
				(type default)
			)
			(layer "B.Fab")
		)
		(fp_line
			(start -0.120396 0.2794)
			(end 0.12065 0.2794)
			(stroke
				(width 0.1)
				(type default)
			)
			(layer "B.Fab")
		)
		(fp_line
			(start -0.120396 0.3048)
			(end -0.120396 0.2794)
			(stroke
				(width 0.1)
				(type default)
			)
			(layer "B.Fab")
		)
		(fp_line
			(start 0.12065 -0.305054)
			(end 0.12065 -0.2794)
			(stroke
				(width 0.1)
				(type default)
			)
			(layer "B.Fab")
		)
		(fp_line
			(start 0.12065 -0.2794)
			(end -0.12065 -0.2794)
			(stroke
				(width 0.1)
				(type default)
			)
			(layer "B.Fab")
		)
		(fp_line
			(start 0.12065 0.2794)
			(end 0.12065 0.3048)
			(stroke
				(width 0.1)
				(type default)
			)
			(layer "B.Fab")
		)
		(fp_line
			(start 0.12065 0.3048)
			(end 0.67945 0.3048)
			(stroke
				(width 0.1)
				(type default)
			)
			(layer "B.Fab")
		)
		(fp_line
			(start 0.67945 -0.305054)
			(end 0.12065 -0.305054)
			(stroke
				(width 0.1)
				(type default)
			)
			(layer "B.Fab")
		)
		(fp_line
			(start 0.67945 0.3048)
			(end 0.67945 -0.305054)
			(stroke
				(width 0.1)
				(type default)
			)
			(layer "B.Fab")
		)
		(pad "1" smd circle
			(at 0.40005 0 180)
			(size 0 0)
			(layers "B.Cu" "B.Mask" "B.Paste")
			(net "SMB_P52V_HPDB_SCL")
		)
		(pad "2" smd circle
			(at -0.40005 0 180)
			(size 0 0)
			(layers "B.Cu" "B.Mask" "B.Paste")
			(net "SMB_P52V_HPDB_R_SCL")
		)
	)
	(footprint ""
		(layer "B.Cu")
		(at 275.169122 -89.520522)
		(property "Reference" "PC564"
			(at 0 0 0)
			(layer "B.SilkS")
			(hide yes)
			(effects
				(font
					(size 1.27 1.27)
				)
				(justify mirror)
			)
		)
		(property "Value" ""
			(at 0 0 0)
			(layer "B.Fab")
			(effects
				(font
					(size 1.27 1.27)
				)
				(justify mirror)
			)
		)
		(duplicate_pad_numbers_are_jumpers no)
		(fp_line
			(start -1.2954 -0.5842)
			(end -1.2954 0.5842)
			(stroke
				(width 0.1524)
				(type default)
			)
			(layer "B.SilkS")
		)
		(fp_line
			(start -1.2954 0.5842)
			(end 1.2954 0.5842)
			(stroke
				(width 0.1524)
				(type default)
			)
			(layer "B.SilkS")
		)
		(fp_line
			(start 1.2954 -0.5842)
			(end -1.2954 -0.5842)
			(stroke
				(width 0.1524)
				(type default)
			)
			(layer "B.SilkS")
		)
		(fp_line
			(start 1.2954 0.5842)
			(end 1.2954 -0.5842)
			(stroke
				(width 0.1524)
				(type default)
			)
			(layer "B.SilkS")
		)
		(fp_line
			(start -1.1938 -0.4064)
			(end -1.1938 0.4064)
			(stroke
				(width 0.1)
				(type default)
			)
			(layer "B.Fab")
		)
		(fp_line
			(start -1.1938 0.4064)
			(end -0.8636 0.4064)
			(stroke
				(width 0.1)
				(type default)
			)
			(layer "B.Fab")
		)
		(fp_line
			(start -0.8636 -0.4572)
			(end -0.8636 -0.4064)
			(stroke
				(width 0.1)
				(type default)
			)
			(layer "B.Fab")
		)
		(fp_line
			(start -0.8636 -0.4064)
			(end -1.1938 -0.4064)
			(stroke
				(width 0.1)
				(type default)
			)
			(layer "B.Fab")
		)
		(fp_line
			(start -0.8636 0.4064)
			(end -0.8636 0.4572)
			(stroke
				(width 0.1)
				(type default)
			)
			(layer "B.Fab")
		)
		(fp_line
			(start -0.8636 0.4572)
			(end 0.8636 0.4572)
			(stroke
				(width 0.1)
				(type default)
			)
			(layer "B.Fab")
		)
		(fp_line
			(start 0.8636 -0.4572)
			(end -0.8636 -0.4572)
			(stroke
				(width 0.1)
				(type default)
			)
			(layer "B.Fab")
		)
		(fp_line
			(start 0.8636 -0.4064)
			(end 0.8636 -0.4572)
			(stroke
				(width 0.1)
				(type default)
			)
			(layer "B.Fab")
		)
		(fp_line
			(start 0.8636 0.4064)
			(end 1.1938 0.4064)
			(stroke
				(width 0.1)
				(type default)
			)
			(layer "B.Fab")
		)
		(fp_line
			(start 0.8636 0.4572)
			(end 0.8636 0.4064)
			(stroke
				(width 0.1)
				(type default)
			)
			(layer "B.Fab")
		)
		(fp_line
			(start 1.1938 -0.4064)
			(end 0.8636 -0.4064)
			(stroke
				(width 0.1)
				(type default)
			)
			(layer "B.Fab")
		)
		(fp_line
			(start 1.1938 0.4064)
			(end 1.1938 -0.4064)
			(stroke
				(width 0.1)
				(type default)
			)
			(layer "B.Fab")
		)
		(pad "1" smd rect
			(at 0.7366 0 270)
			(size 0.7112 0.8128)
			(layers "B.Cu" "B.Mask" "B.Paste")
			(net "P52V_HS1_4287_GATE2_R")
		)
		(pad "2" smd rect
			(at -0.7366 0 270)
			(size 0.7112 0.8128)
			(layers "B.Cu" "B.Mask" "B.Paste")
			(net "P52V_HS")
		)
	)
	(footprint ""
		(layer "B.Cu")
		(at 224.79 -95.504 90)
		(property "Reference" "C22"
			(at 0 0 90)
			(layer "B.SilkS")
			(hide yes)
			(effects
				(font
					(size 1.27 1.27)
				)
				(justify mirror)
			)
		)
		(property "Value" ""
			(at 0 0 90)
			(layer "B.Fab")
			(effects
				(font
					(size 1.27 1.27)
				)
				(justify mirror)
			)
		)
		(duplicate_pad_numbers_are_jumpers no)
		(fp_line
			(start 2.2098 -0.9398)
			(end -2.2098 -0.9398)
			(stroke
				(width 0.1524)
				(type default)
			)
			(layer "B.SilkS")
		)
		(fp_line
			(start -2.2098 -0.9398)
			(end -2.2098 0.9398)
			(stroke
				(width 0.1524)
				(type default)
			)
			(layer "B.SilkS")
		)
		(fp_line
			(start 2.2098 0.9398)
			(end 2.2098 -0.9398)
			(stroke
				(width 0.1524)
				(type default)
			)
			(layer "B.SilkS")
		)
		(fp_line
			(start -2.2098 0.9398)
			(end 2.2098 0.9398)
			(stroke
				(width 0.1524)
				(type default)
			)
			(layer "B.SilkS")
		)
		(fp_line
			(start 1.700022 -0.899922)
			(end -1.700022 -0.899922)
			(stroke
				(width 0.1)
				(type default)
			)
			(layer "B.Fab")
		)
		(fp_line
			(start -1.700022 -0.899922)
			(end -1.700022 0.899922)
			(stroke
				(width 0.1)
				(type default)
			)
			(layer "B.Fab")
		)
		(fp_line
			(start 1.700022 0.899922)
			(end 1.700022 -0.899922)
			(stroke
				(width 0.1)
				(type default)
			)
			(layer "B.Fab")
		)
		(fp_line
			(start -1.700022 0.899922)
			(end 1.700022 0.899922)
			(stroke
				(width 0.1)
				(type default)
			)
			(layer "B.Fab")
		)
		(pad "1" smd rect
			(at 1.4732 0 90)
			(size 1.1684 1.5748)
			(layers "B.Cu" "B.Mask" "B.Paste")
			(net "P52V_HS")
		)
		(pad "2" smd rect
			(at -1.4732 0 90)
			(size 1.1684 1.5748)
			(layers "B.Cu" "B.Mask" "B.Paste")
			(net "GND")
		)
	)
	(footprint ""
		(layer "B.Cu")
		(at 182.850282 -76.708 -90)
		(property "Reference" "PR318"
			(at 0 0 90)
			(layer "B.SilkS")
			(hide yes)
			(effects
				(font
					(size 1.27 1.27)
				)
				(justify mirror)
			)
		)
		(property "Value" ""
			(at 0 0 90)
			(layer "B.Fab")
			(effects
				(font
					(size 1.27 1.27)
				)
				(justify mirror)
			)
		)
		(duplicate_pad_numbers_are_jumpers no)
		(fp_line
			(start -0.7874 0.4064)
			(end 0.7874 0.4064)
			(stroke
				(width 0.1524)
				(type default)
			)
			(layer "B.SilkS")
		)
		(fp_line
			(start 0.7874 0.4064)
			(end 0.7874 -0.4064)
			(stroke
				(width 0.1524)
				(type default)
			)
			(layer "B.SilkS")
		)
		(fp_line
			(start -0.7874 -0.4064)
			(end -0.7874 0.4064)
			(stroke
				(width 0.1524)
				(type default)
			)
			(layer "B.SilkS")
		)
		(fp_line
			(start 0.7874 -0.4064)
			(end -0.7874 -0.4064)
			(stroke
				(width 0.1524)
				(type default)
			)
			(layer "B.SilkS")
		)
		(fp_line
			(start -0.67945 0.3048)
			(end -0.120396 0.3048)
			(stroke
				(width 0.1)
				(type default)
			)
			(layer "B.Fab")
		)
		(fp_line
			(start -0.120396 0.3048)
			(end -0.120396 0.2794)
			(stroke
				(width 0.1)
				(type default)
			)
			(layer "B.Fab")
		)
		(fp_line
			(start 0.12065 0.3048)
			(end 0.67945 0.3048)
			(stroke
				(width 0.1)
				(type default)
			)
			(layer "B.Fab")
		)
		(fp_line
			(start 0.67945 0.3048)
			(end 0.67945 -0.305054)
			(stroke
				(width 0.1)
				(type default)
			)
			(layer "B.Fab")
		)
		(fp_line
			(start -0.120396 0.2794)
			(end 0.12065 0.2794)
			(stroke
				(width 0.1)
				(type default)
			)
			(layer "B.Fab")
		)
		(fp_line
			(start 0.12065 0.2794)
			(end 0.12065 0.3048)
			(stroke
				(width 0.1)
				(type default)
			)
			(layer "B.Fab")
		)
		(fp_line
			(start -0.12065 -0.2794)
			(end -0.12065 -0.3048)
			(stroke
				(width 0.1)
				(type default)
			)
			(layer "B.Fab")
		)
		(fp_line
			(start 0.12065 -0.2794)
			(end -0.12065 -0.2794)
			(stroke
				(width 0.1)
				(type default)
			)
			(layer "B.Fab")
		)
		(fp_line
			(start -0.67945 -0.3048)
			(end -0.67945 0.3048)
			(stroke
				(width 0.1)
				(type default)
			)
			(layer "B.Fab")
		)
		(fp_line
			(start -0.12065 -0.3048)
			(end -0.67945 -0.3048)
			(stroke
				(width 0.1)
				(type default)
			)
			(layer "B.Fab")
		)
		(fp_line
			(start 0.12065 -0.305054)
			(end 0.12065 -0.2794)
			(stroke
				(width 0.1)
				(type default)
			)
			(layer "B.Fab")
		)
		(fp_line
			(start 0.67945 -0.305054)
			(end 0.12065 -0.305054)
			(stroke
				(width 0.1)
				(type default)
			)
			(layer "B.Fab")
		)
		(pad "1" smd rect
			(at 0.40005 0 270)
			(size 0.4572 0.508)
			(layers "B.Cu" "B.Mask" "B.Paste")
			(net "P12V_MB2_SENSE+")
		)
		(pad "2" smd rect
			(at -0.40005 0 270)
			(size 0.4572 0.508)
			(layers "B.Cu" "B.Mask" "B.Paste")
			(net "P12V_BRICK")
		)
	)
	(footprint ""
		(layer "B.Cu")
		(at 238.047784 -84.17179 90)
		(property "Reference" "U1"
			(at -0.47879 -2.235454 270)
			(unlocked yes)
			(layer "B.SilkS")
			(effects
				(font
					(size 0.7874 0.5842)
					(thickness 0.1524)
				)
				(justify left mirror)
			)
		)
		(property "Value" ""
			(at 0 0 90)
			(layer "B.Fab")
			(effects
				(font
					(size 1.27 1.27)
				)
				(justify mirror)
			)
		)
		(duplicate_pad_numbers_are_jumpers no)
		(fp_line
			(start 1.3716 -1.524)
			(end 0.508 -1.524)
			(stroke
				(width 0.1524)
				(type default)
			)
			(layer "B.SilkS")
		)
		(fp_line
			(start 0.508 -1.524)
			(end 0 -1.016)
			(stroke
				(width 0.1524)
				(type default)
			)
			(layer "B.SilkS")
		)
		(fp_line
			(start -0.508 -1.524)
			(end -1.3716 -1.524)
			(stroke
				(width 0.1524)
				(type default)
			)
			(layer "B.SilkS")
		)
		(fp_line
			(start -1.3716 -1.524)
			(end -1.3716 1.524)
			(stroke
				(width 0.1524)
				(type default)
			)
			(layer "B.SilkS")
		)
		(fp_line
			(start 0 -1.016)
			(end -0.508 -1.524)
			(stroke
				(width 0.1524)
				(type default)
			)
			(layer "B.SilkS")
		)
		(fp_line
			(start 1.3716 1.524)
			(end 1.3716 -1.524)
			(stroke
				(width 0.1524)
				(type default)
			)
			(layer "B.SilkS")
		)
		(fp_line
			(start -1.3716 1.524)
			(end 1.3716 1.524)
			(stroke
				(width 0.1524)
				(type default)
			)
			(layer "B.SilkS")
		)
		(fp_poly
			(pts
				(xy 2.661666 -2.352294) (xy 2.036826 -2.352294) (xy 2.364994 -1.798574)
			)
			(stroke
				(width 0)
				(type default)
			)
			(fill yes)
			(layer "B.SilkS")
		)
		(fp_line
			(start 1.5494 -1.524)
			(end -1.5494 -1.524)
			(stroke
				(width 0.1)
				(type default)
			)
			(layer "B.Fab")
		)
		(fp_line
			(start -1.5494 -1.524)
			(end -1.5494 -1.0668)
			(stroke
				(width 0.1)
				(type default)
			)
			(layer "B.Fab")
		)
		(fp_line
			(start 2.54 -1.0668)
			(end 1.5494 -1.0668)
			(stroke
				(width 0.1)
				(type default)
			)
			(layer "B.Fab")
		)
		(fp_line
			(start 1.5494 -1.0668)
			(end 1.5494 -1.524)
			(stroke
				(width 0.1)
				(type default)
			)
			(layer "B.Fab")
		)
		(fp_line
			(start -1.5494 -1.0668)
			(end -2.54 -1.0668)
			(stroke
				(width 0.1)
				(type default)
			)
			(layer "B.Fab")
		)
		(fp_line
			(start -1.5494 -1.0668)
			(end -1.5494 1.0668)
			(stroke
				(width 0.1)
				(type default)
			)
			(layer "B.Fab")
		)
		(fp_line
			(start -2.54 -1.0668)
			(end -2.54 1.0668)
			(stroke
				(width 0.1)
				(type default)
			)
			(layer "B.Fab")
		)
		(fp_line
			(start 2.54 1.0668)
			(end 2.54 -1.0668)
			(stroke
				(width 0.1)
				(type default)
			)
			(layer "B.Fab")
		)
		(fp_line
			(start 1.5494 1.0668)
			(end 1.5494 -1.0668)
			(stroke
				(width 0.1)
				(type default)
			)
			(layer "B.Fab")
		)
		(fp_line
			(start 1.5494 1.0668)
			(end 2.54 1.0668)
			(stroke
				(width 0.1)
				(type default)
			)
			(layer "B.Fab")
		)
		(fp_line
			(start -1.5494 1.0668)
			(end -1.5494 1.524)
			(stroke
				(width 0.1)
				(type default)
			)
			(layer "B.Fab")
		)
		(fp_line
			(start -2.54 1.0668)
			(end -1.5494 1.0668)
			(stroke
				(width 0.1)
				(type default)
			)
			(layer "B.Fab")
		)
		(fp_line
			(start 1.5494 1.524)
			(end 1.5494 1.0668)
			(stroke
				(width 0.1)
				(type default)
			)
			(layer "B.Fab")
		)
		(fp_line
			(start -1.5494 1.524)
			(end 1.5494 1.524)
			(stroke
				(width 0.1)
				(type default)
			)
			(layer "B.Fab")
		)
		(fp_poly
			(pts
				(xy 3.60172 -0.719328) (xy 3.60172 -1.344168) (xy 3.048 -1.016)
			)
			(stroke
				(width 0)
				(type default)
			)
			(fill yes)
			(layer "B.Fab")
		)
		(pad "1" smd rect
			(at 2.232406 -0.975106)
			(size 0.3556 1.4224)
			(layers "B.Cu" "B.Mask" "B.Paste")
			(net "MB_MISC_I2C_EN")
		)
		(pad "2" smd rect
			(at 2.232406 -0.32512)
			(size 0.3556 1.4224)
			(layers "B.Cu" "B.Mask" "B.Paste")
			(net "SMB_PDB_MISC_SCL_R")
		)
		(pad "3" smd rect
			(at 2.232406 0.32512)
			(size 0.3556 1.4224)
			(layers "B.Cu" "B.Mask" "B.Paste")
			(net "SMB_MB_PDB_SCL")
		)
		(pad "4" smd rect
			(at 2.232406 0.975106)
			(size 0.3556 1.4224)
			(layers "B.Cu" "B.Mask" "B.Paste")
			(net "GND")
		)
		(pad "5" smd rect
			(at -2.232406 0.975106)
			(size 0.3556 1.4224)
			(layers "B.Cu" "B.Mask" "B.Paste")
			(net "NC_U1_READY")
		)
		(pad "6" smd rect
			(at -2.232406 0.32512)
			(size 0.3556 1.4224)
			(layers "B.Cu" "B.Mask" "B.Paste")
			(net "SMB_MB_PDB_SDA")
		)
		(pad "7" smd rect
			(at -2.232406 -0.32512)
			(size 0.3556 1.4224)
			(layers "B.Cu" "B.Mask" "B.Paste")
			(net "SMB_PDB_MISC_SDA_R")
		)
		(pad "8" smd rect
			(at -2.232406 -0.975106)
			(size 0.3556 1.4224)
			(layers "B.Cu" "B.Mask" "B.Paste")
			(net "P3V3_AUX")
		)
	)
)
